(kicad_pcb
	(version 20260206)
	(generator "pcbnew")
	(generator_version "10.0")
	(general
		(thickness 1.6)
		(legacy_teardrops no)
	)
	(paper "A4")
	(title_block
		(title "04192023_DAF0TMB3IC0_F0TG_MB_C_brd_V02_OCP.brd")
		(comment 1 "Grand Teton / footprints 6616-6622 of 8354")
	)
	(layers
		(0 "F.Cu" signal "TOP")
		(4 "In1.Cu" signal "GND")
		(6 "In2.Cu" signal "IN1")
		(8 "In3.Cu" signal "GND1")
		(10 "In4.Cu" signal "IN2")
		(12 "In5.Cu" signal "GND2")
		(14 "In6.Cu" signal "IN3")
		(16 "In7.Cu" signal "GND3")
		(18 "In8.Cu" signal "VCC")
		(20 "In9.Cu" signal "VCC1")
		(22 "In10.Cu" signal "GND4")
		(24 "In11.Cu" signal "IN4")
		(26 "In12.Cu" signal "GND5")
		(28 "In13.Cu" signal "IN5")
		(30 "In14.Cu" signal "GND6")
		(32 "In15.Cu" signal "IN6")
		(34 "In16.Cu" signal "GND7")
		(2 "B.Cu" signal "BOTTOM")
		(9 "F.Adhes" user "F.Adhesive")
		(11 "B.Adhes" user "B.Adhesive")
		(13 "F.Paste" user "Package Geometry/Pastemask Top")
		(15 "B.Paste" user "Package Geometry/Pastemask Bottom")
		(5 "F.SilkS" user "Ref Des/Silkscreen Top")
		(7 "B.SilkS" user "Ref Des/Silkscreen Bottom")
		(1 "F.Mask" user "Board Geometry/Soldermask Top")
		(3 "B.Mask" user "Board Geometry/Soldermask Bottom")
		(17 "Dwgs.User" user "User.Drawings")
		(19 "Cmts.User" user "User.Comments")
		(21 "Eco1.User" user "User.Eco1")
		(23 "Eco2.User" user "User.Eco2")
		(25 "Edge.Cuts" user "Board Geometry/Outline")
		(27 "Margin" user)
		(31 "F.CrtYd" user "Package Geometry/Place Bound Top")
		(29 "B.CrtYd" user "Package Geometry/Place Bound Bottom")
		(35 "F.Fab" user "Ref Des/Assembly Top")
		(33 "B.Fab" user "Ref Des/Assembly Bottom")
	)
	(footprint ""
		(layer "B.Cu")
		(at 430.80051 -195.85051 180)
		(property "Reference" "R1683"
			(at 0 0 0)
			(layer "B.SilkS")
			(hide yes)
			(effects
				(font
					(size 1.27 1.27)
				)
				(justify mirror)
			)
		)
		(property "Value" ""
			(at 0 0 0)
			(layer "B.Fab")
			(effects
				(font
					(size 1.27 1.27)
				)
				(justify mirror)
			)
		)
		(duplicate_pad_numbers_are_jumpers no)
		(fp_line
			(start 0.7874 0.4064)
			(end 0.7874 -0.4064)
			(stroke
				(width 0.1524)
				(type default)
			)
			(layer "B.SilkS")
		)
		(fp_line
			(start 0.7874 -0.4064)
			(end -0.7874 -0.4064)
			(stroke
				(width 0.1524)
				(type default)
			)
			(layer "B.SilkS")
		)
		(fp_line
			(start -0.7874 0.4064)
			(end 0.7874 0.4064)
			(stroke
				(width 0.1524)
				(type default)
			)
			(layer "B.SilkS")
		)
		(fp_line
			(start -0.7874 -0.4064)
			(end -0.7874 0.4064)
			(stroke
				(width 0.1524)
				(type default)
			)
			(layer "B.SilkS")
		)
		(fp_line
			(start 0.67945 0.3048)
			(end 0.67945 -0.305054)
			(stroke
				(width 0.1)
				(type default)
			)
			(layer "B.Fab")
		)
		(fp_line
			(start 0.67945 -0.305054)
			(end 0.12065 -0.305054)
			(stroke
				(width 0.1)
				(type default)
			)
			(layer "B.Fab")
		)
		(fp_line
			(start 0.12065 0.3048)
			(end 0.67945 0.3048)
			(stroke
				(width 0.1)
				(type default)
			)
			(layer "B.Fab")
		)
		(fp_line
			(start 0.12065 0.2794)
			(end 0.12065 0.3048)
			(stroke
				(width 0.1)
				(type default)
			)
			(layer "B.Fab")
		)
		(fp_line
			(start 0.12065 -0.2794)
			(end -0.12065 -0.2794)
			(stroke
				(width 0.1)
				(type default)
			)
			(layer "B.Fab")
		)
		(fp_line
			(start 0.12065 -0.305054)
			(end 0.12065 -0.2794)
			(stroke
				(width 0.1)
				(type default)
			)
			(layer "B.Fab")
		)
		(fp_line
			(start -0.120396 0.3048)
			(end -0.120396 0.2794)
			(stroke
				(width 0.1)
				(type default)
			)
			(layer "B.Fab")
		)
		(fp_line
			(start -0.120396 0.2794)
			(end 0.12065 0.2794)
			(stroke
				(width 0.1)
				(type default)
			)
			(layer "B.Fab")
		)
		(fp_line
			(start -0.12065 -0.2794)
			(end -0.12065 -0.3048)
			(stroke
				(width 0.1)
				(type default)
			)
			(layer "B.Fab")
		)
		(fp_line
			(start -0.12065 -0.3048)
			(end -0.67945 -0.3048)
			(stroke
				(width 0.1)
				(type default)
			)
			(layer "B.Fab")
		)
		(fp_line
			(start -0.67945 0.3048)
			(end -0.120396 0.3048)
			(stroke
				(width 0.1)
				(type default)
			)
			(layer "B.Fab")
		)
		(fp_line
			(start -0.67945 -0.3048)
			(end -0.67945 0.3048)
			(stroke
				(width 0.1)
				(type default)
			)
			(layer "B.Fab")
		)
		(pad "1" smd circle
			(at 0.40005 0)
			(size 0 0)
			(layers "B.Cu" "B.Mask" "B.Paste")
			(net "I3C_SPD_DDRGL_CPU0_SDA")
		)
		(pad "2" smd circle
			(at -0.40005 0)
			(size 0 0)
			(layers "B.Cu" "B.Mask" "B.Paste")
			(net "I3C_SPD_DDRI_CPU0_SDA")
		)
	)
	(footprint ""
		(layer "B.Cu")
		(at 58.1914 -390.560052 90)
		(property "Reference" "C244"
			(at 0 0 90)
			(layer "B.SilkS")
			(hide yes)
			(effects
				(font
					(size 1.27 1.27)
				)
				(justify mirror)
			)
		)
		(property "Value" ""
			(at 0 0 90)
			(layer "B.Fab")
			(effects
				(font
					(size 1.27 1.27)
				)
				(justify mirror)
			)
		)
		(duplicate_pad_numbers_are_jumpers no)
		(fp_line
			(start 0.7874 -0.4064)
			(end -0.7874 -0.4064)
			(stroke
				(width 0.1524)
				(type default)
			)
			(layer "B.SilkS")
		)
		(fp_line
			(start -0.7874 -0.4064)
			(end -0.7874 0.4064)
			(stroke
				(width 0.1524)
				(type default)
			)
			(layer "B.SilkS")
		)
		(fp_line
			(start 0.7874 0.4064)
			(end 0.7874 -0.4064)
			(stroke
				(width 0.1524)
				(type default)
			)
			(layer "B.SilkS")
		)
		(fp_line
			(start -0.7874 0.4064)
			(end 0.7874 0.4064)
			(stroke
				(width 0.1524)
				(type default)
			)
			(layer "B.SilkS")
		)
		(fp_line
			(start 0.67945 -0.305054)
			(end 0.12065 -0.305054)
			(stroke
				(width 0.1)
				(type default)
			)
			(layer "B.Fab")
		)
		(fp_line
			(start 0.12065 -0.305054)
			(end 0.12065 -0.2794)
			(stroke
				(width 0.1)
				(type default)
			)
			(layer "B.Fab")
		)
		(fp_line
			(start -0.12065 -0.3048)
			(end -0.67945 -0.3048)
			(stroke
				(width 0.1)
				(type default)
			)
			(layer "B.Fab")
		)
		(fp_line
			(start -0.67945 -0.3048)
			(end -0.67945 0.3048)
			(stroke
				(width 0.1)
				(type default)
			)
			(layer "B.Fab")
		)
		(fp_line
			(start 0.12065 -0.2794)
			(end -0.12065 -0.2794)
			(stroke
				(width 0.1)
				(type default)
			)
			(layer "B.Fab")
		)
		(fp_line
			(start -0.12065 -0.2794)
			(end -0.12065 -0.3048)
			(stroke
				(width 0.1)
				(type default)
			)
			(layer "B.Fab")
		)
		(fp_line
			(start 0.12065 0.2794)
			(end 0.12065 0.3048)
			(stroke
				(width 0.1)
				(type default)
			)
			(layer "B.Fab")
		)
		(fp_line
			(start -0.120396 0.2794)
			(end 0.12065 0.2794)
			(stroke
				(width 0.1)
				(type default)
			)
			(layer "B.Fab")
		)
		(fp_line
			(start 0.67945 0.3048)
			(end 0.67945 -0.305054)
			(stroke
				(width 0.1)
				(type default)
			)
			(layer "B.Fab")
		)
		(fp_line
			(start 0.12065 0.3048)
			(end 0.67945 0.3048)
			(stroke
				(width 0.1)
				(type default)
			)
			(layer "B.Fab")
		)
		(fp_line
			(start -0.120396 0.3048)
			(end -0.120396 0.2794)
			(stroke
				(width 0.1)
				(type default)
			)
			(layer "B.Fab")
		)
		(fp_line
			(start -0.67945 0.3048)
			(end -0.120396 0.3048)
			(stroke
				(width 0.1)
				(type default)
			)
			(layer "B.Fab")
		)
		(pad "1" smd circle
			(at 0.40005 0 270)
			(size 0 0)
			(layers "B.Cu" "B.Mask" "B.Paste")
			(net "P0V9_CPU1_RT_2D")
		)
		(pad "2" smd circle
			(at -0.40005 0 270)
			(size 0 0)
			(layers "B.Cu" "B.Mask" "B.Paste")
			(net "GND")
		)
	)
	(footprint ""
		(layer "B.Cu")
		(at 164.325554 -348.180406)
		(property "Reference" "PR415"
			(at 0 0 0)
			(layer "B.SilkS")
			(hide yes)
			(effects
				(font
					(size 1.27 1.27)
				)
				(justify mirror)
			)
		)
		(property "Value" ""
			(at 0 0 0)
			(layer "B.Fab")
			(effects
				(font
					(size 1.27 1.27)
				)
				(justify mirror)
			)
		)
		(duplicate_pad_numbers_are_jumpers no)
		(fp_line
			(start -0.7874 -0.4064)
			(end -0.7874 0.4064)
			(stroke
				(width 0.1524)
				(type default)
			)
			(layer "B.SilkS")
		)
		(fp_line
			(start -0.7874 0.4064)
			(end 0.7874 0.4064)
			(stroke
				(width 0.1524)
				(type default)
			)
			(layer "B.SilkS")
		)
		(fp_line
			(start 0.7874 -0.4064)
			(end -0.7874 -0.4064)
			(stroke
				(width 0.1524)
				(type default)
			)
			(layer "B.SilkS")
		)
		(fp_line
			(start 0.7874 0.4064)
			(end 0.7874 -0.4064)
			(stroke
				(width 0.1524)
				(type default)
			)
			(layer "B.SilkS")
		)
		(fp_line
			(start -0.67945 -0.3048)
			(end -0.67945 0.3048)
			(stroke
				(width 0.1)
				(type default)
			)
			(layer "B.Fab")
		)
		(fp_line
			(start -0.67945 0.3048)
			(end -0.120396 0.3048)
			(stroke
				(width 0.1)
				(type default)
			)
			(layer "B.Fab")
		)
		(fp_line
			(start -0.12065 -0.3048)
			(end -0.67945 -0.3048)
			(stroke
				(width 0.1)
				(type default)
			)
			(layer "B.Fab")
		)
		(fp_line
			(start -0.12065 -0.2794)
			(end -0.12065 -0.3048)
			(stroke
				(width 0.1)
				(type default)
			)
			(layer "B.Fab")
		)
		(fp_line
			(start -0.120396 0.2794)
			(end 0.12065 0.2794)
			(stroke
				(width 0.1)
				(type default)
			)
			(layer "B.Fab")
		)
		(fp_line
			(start -0.120396 0.3048)
			(end -0.120396 0.2794)
			(stroke
				(width 0.1)
				(type default)
			)
			(layer "B.Fab")
		)
		(fp_line
			(start 0.12065 -0.305054)
			(end 0.12065 -0.2794)
			(stroke
				(width 0.1)
				(type default)
			)
			(layer "B.Fab")
		)
		(fp_line
			(start 0.12065 -0.2794)
			(end -0.12065 -0.2794)
			(stroke
				(width 0.1)
				(type default)
			)
			(layer "B.Fab")
		)
		(fp_line
			(start 0.12065 0.2794)
			(end 0.12065 0.3048)
			(stroke
				(width 0.1)
				(type default)
			)
			(layer "B.Fab")
		)
		(fp_line
			(start 0.12065 0.3048)
			(end 0.67945 0.3048)
			(stroke
				(width 0.1)
				(type default)
			)
			(layer "B.Fab")
		)
		(fp_line
			(start 0.67945 -0.305054)
			(end 0.12065 -0.305054)
			(stroke
				(width 0.1)
				(type default)
			)
			(layer "B.Fab")
		)
		(fp_line
			(start 0.67945 0.3048)
			(end 0.67945 -0.305054)
			(stroke
				(width 0.1)
				(type default)
			)
			(layer "B.Fab")
		)
		(pad "1" smd circle
			(at 0.40005 0 180)
			(size 0 0)
			(layers "B.Cu" "B.Mask" "B.Paste")
			(net "PVDD11_S3_P1_TEMP1")
		)
		(pad "2" smd circle
			(at -0.40005 0 180)
			(size 0 0)
			(layers "B.Cu" "B.Mask" "B.Paste")
			(net "GND")
		)
	)
	(footprint ""
		(layer "B.Cu")
		(at 117.102128 -28.457906 180)
		(property "Reference" "C6119"
			(at 0 0 0)
			(layer "B.SilkS")
			(hide yes)
			(effects
				(font
					(size 1.27 1.27)
				)
				(justify mirror)
			)
		)
		(property "Value" ""
			(at 0 0 0)
			(layer "B.Fab")
			(effects
				(font
					(size 1.27 1.27)
				)
				(justify mirror)
			)
		)
		(duplicate_pad_numbers_are_jumpers no)
		(fp_line
			(start 0.7874 0.4064)
			(end 0.7874 -0.4064)
			(stroke
				(width 0.1524)
				(type default)
			)
			(layer "B.SilkS")
		)
		(fp_line
			(start 0.7874 -0.4064)
			(end -0.7874 -0.4064)
			(stroke
				(width 0.1524)
				(type default)
			)
			(layer "B.SilkS")
		)
		(fp_line
			(start -0.7874 0.4064)
			(end 0.7874 0.4064)
			(stroke
				(width 0.1524)
				(type default)
			)
			(layer "B.SilkS")
		)
		(fp_line
			(start -0.7874 -0.4064)
			(end -0.7874 0.4064)
			(stroke
				(width 0.1524)
				(type default)
			)
			(layer "B.SilkS")
		)
		(fp_line
			(start 0.67945 0.3048)
			(end 0.67945 -0.305054)
			(stroke
				(width 0.1)
				(type default)
			)
			(layer "B.Fab")
		)
		(fp_line
			(start 0.67945 -0.305054)
			(end 0.12065 -0.305054)
			(stroke
				(width 0.1)
				(type default)
			)
			(layer "B.Fab")
		)
		(fp_line
			(start 0.12065 0.3048)
			(end 0.67945 0.3048)
			(stroke
				(width 0.1)
				(type default)
			)
			(layer "B.Fab")
		)
		(fp_line
			(start 0.12065 0.2794)
			(end 0.12065 0.3048)
			(stroke
				(width 0.1)
				(type default)
			)
			(layer "B.Fab")
		)
		(fp_line
			(start 0.12065 -0.2794)
			(end -0.12065 -0.2794)
			(stroke
				(width 0.1)
				(type default)
			)
			(layer "B.Fab")
		)
		(fp_line
			(start 0.12065 -0.305054)
			(end 0.12065 -0.2794)
			(stroke
				(width 0.1)
				(type default)
			)
			(layer "B.Fab")
		)
		(fp_line
			(start -0.120396 0.3048)
			(end -0.120396 0.2794)
			(stroke
				(width 0.1)
				(type default)
			)
			(layer "B.Fab")
		)
		(fp_line
			(start -0.120396 0.2794)
			(end 0.12065 0.2794)
			(stroke
				(width 0.1)
				(type default)
			)
			(layer "B.Fab")
		)
		(fp_line
			(start -0.12065 -0.2794)
			(end -0.12065 -0.3048)
			(stroke
				(width 0.1)
				(type default)
			)
			(layer "B.Fab")
		)
		(fp_line
			(start -0.12065 -0.3048)
			(end -0.67945 -0.3048)
			(stroke
				(width 0.1)
				(type default)
			)
			(layer "B.Fab")
		)
		(fp_line
			(start -0.67945 0.3048)
			(end -0.120396 0.3048)
			(stroke
				(width 0.1)
				(type default)
			)
			(layer "B.Fab")
		)
		(fp_line
			(start -0.67945 -0.3048)
			(end -0.67945 0.3048)
			(stroke
				(width 0.1)
				(type default)
			)
			(layer "B.Fab")
		)
		(pad "1" smd circle
			(at 0.40005 0)
			(size 0 0)
			(layers "B.Cu" "B.Mask" "B.Paste")
			(net "P1V2_CPU0_USB2_DVDD12")
		)
		(pad "2" smd circle
			(at -0.40005 0)
			(size 0 0)
			(layers "B.Cu" "B.Mask" "B.Paste")
			(net "GND")
		)
	)
	(footprint ""
		(layer "B.Cu")
		(at 114.478562 -386.766562 90)
		(property "Reference" "C455"
			(at 0 0 90)
			(layer "B.SilkS")
			(hide yes)
			(effects
				(font
					(size 1.27 1.27)
				)
				(justify mirror)
			)
		)
		(property "Value" ""
			(at 0 0 90)
			(layer "B.Fab")
			(effects
				(font
					(size 1.27 1.27)
				)
				(justify mirror)
			)
		)
		(duplicate_pad_numbers_are_jumpers no)
		(fp_line
			(start 0.299974 -0.150114)
			(end -0.299974 -0.150114)
			(stroke
				(width 0.1)
				(type default)
			)
			(layer "B.Fab")
		)
		(fp_line
			(start -0.299974 -0.150114)
			(end -0.299974 0.150114)
			(stroke
				(width 0.1)
				(type default)
			)
			(layer "B.Fab")
		)
		(fp_line
			(start 0.299974 0.150114)
			(end 0.299974 -0.150114)
			(stroke
				(width 0.1)
				(type default)
			)
			(layer "B.Fab")
		)
		(fp_line
			(start -0.299974 0.150114)
			(end 0.299974 0.150114)
			(stroke
				(width 0.1)
				(type default)
			)
			(layer "B.Fab")
		)
		(pad "1" smd rect
			(at 0.2667 0 270)
			(size 0.3048 0.381)
			(layers "B.Cu" "B.Mask" "B.Paste")
			(net "P0V9_CPU1_RT3_2A")
		)
		(pad "2" smd rect
			(at -0.2667 0 270)
			(size 0.3048 0.381)
			(layers "B.Cu" "B.Mask" "B.Paste")
			(net "GND")
		)
	)
	(footprint ""
		(layer "B.Cu")
		(at 58.65241 -149.721824 180)
		(property "Reference" "PC84"
			(at 0 0 0)
			(layer "B.SilkS")
			(hide yes)
			(effects
				(font
					(size 1.27 1.27)
				)
				(justify mirror)
			)
		)
		(property "Value" ""
			(at 0 0 0)
			(layer "B.Fab")
			(effects
				(font
					(size 1.27 1.27)
				)
				(justify mirror)
			)
		)
		(duplicate_pad_numbers_are_jumpers no)
		(fp_line
			(start 1.524 0.762)
			(end 1.524 -0.762)
			(stroke
				(width 0.1524)
				(type default)
			)
			(layer "B.SilkS")
		)
		(fp_line
			(start 1.524 -0.762)
			(end -1.524 -0.762)
			(stroke
				(width 0.1524)
				(type default)
			)
			(layer "B.SilkS")
		)
		(fp_line
			(start -1.524 0.762)
			(end 1.524 0.762)
			(stroke
				(width 0.1524)
				(type default)
			)
			(layer "B.SilkS")
		)
		(fp_line
			(start -1.524 -0.762)
			(end -1.524 0.762)
			(stroke
				(width 0.1524)
				(type default)
			)
			(layer "B.SilkS")
		)
		(fp_line
			(start 1.1049 0.724916)
			(end -1.1049 0.724916)
			(stroke
				(width 0.1)
				(type default)
			)
			(layer "B.Fab")
		)
		(fp_line
			(start 1.1049 -0.724916)
			(end 1.1049 0.724916)
			(stroke
				(width 0.1)
				(type default)
			)
			(layer "B.Fab")
		)
		(fp_line
			(start -1.1049 0.724916)
			(end -1.1049 -0.724916)
			(stroke
				(width 0.1)
				(type default)
			)
			(layer "B.Fab")
		)
		(fp_line
			(start -1.1049 -0.724916)
			(end 1.1049 -0.724916)
			(stroke
				(width 0.1)
				(type default)
			)
			(layer "B.Fab")
		)
		(pad "1" smd rect
			(at 0.889 0 180)
			(size 1.016 1.27)
			(layers "B.Cu" "B.Mask" "B.Paste")
			(net "PVDD18_S5_P1")
		)
		(pad "2" smd rect
			(at -0.889 0 180)
			(size 1.016 1.27)
			(layers "B.Cu" "B.Mask" "B.Paste")
			(net "GND")
		)
	)
	(footprint ""
		(layer "B.Cu")
		(at 445.887602 -418.58311 90)
		(property "Reference" "PR6612"
			(at 0 0 90)
			(layer "B.SilkS")
			(hide yes)
			(effects
				(font
					(size 1.27 1.27)
				)
				(justify mirror)
			)
		)
		(property "Value" ""
			(at 0 0 90)
			(layer "B.Fab")
			(effects
				(font
					(size 1.27 1.27)
				)
				(justify mirror)
			)
		)
		(duplicate_pad_numbers_are_jumpers no)
		(fp_line
			(start 0.7874 -0.4064)
			(end -0.7874 -0.4064)
			(stroke
				(width 0.1524)
				(type default)
			)
			(layer "B.SilkS")
		)
		(fp_line
			(start -0.7874 -0.4064)
			(end -0.7874 0.4064)
			(stroke
				(width 0.1524)
				(type default)
			)
			(layer "B.SilkS")
		)
		(fp_line
			(start 0.7874 0.4064)
			(end 0.7874 -0.4064)
			(stroke
				(width 0.1524)
				(type default)
			)
			(layer "B.SilkS")
		)
		(fp_line
			(start -0.7874 0.4064)
			(end 0.7874 0.4064)
			(stroke
				(width 0.1524)
				(type default)
			)
			(layer "B.SilkS")
		)
		(fp_line
			(start 0.67945 -0.305054)
			(end 0.12065 -0.305054)
			(stroke
				(width 0.1)
				(type default)
			)
			(layer "B.Fab")
		)
		(fp_line
			(start 0.12065 -0.305054)
			(end 0.12065 -0.2794)
			(stroke
				(width 0.1)
				(type default)
			)
			(layer "B.Fab")
		)
		(fp_line
			(start -0.12065 -0.3048)
			(end -0.67945 -0.3048)
			(stroke
				(width 0.1)
				(type default)
			)
			(layer "B.Fab")
		)
		(fp_line
			(start -0.67945 -0.3048)
			(end -0.67945 0.3048)
			(stroke
				(width 0.1)
				(type default)
			)
			(layer "B.Fab")
		)
		(fp_line
			(start 0.12065 -0.2794)
			(end -0.12065 -0.2794)
			(stroke
				(width 0.1)
				(type default)
			)
			(layer "B.Fab")
		)
		(fp_line
			(start -0.12065 -0.2794)
			(end -0.12065 -0.3048)
			(stroke
				(width 0.1)
				(type default)
			)
			(layer "B.Fab")
		)
		(fp_line
			(start 0.12065 0.2794)
			(end 0.12065 0.3048)
			(stroke
				(width 0.1)
				(type default)
			)
			(layer "B.Fab")
		)
		(fp_line
			(start -0.120396 0.2794)
			(end 0.12065 0.2794)
			(stroke
				(width 0.1)
				(type default)
			)
			(layer "B.Fab")
		)
		(fp_line
			(start 0.67945 0.3048)
			(end 0.67945 -0.305054)
			(stroke
				(width 0.1)
				(type default)
			)
			(layer "B.Fab")
		)
		(fp_line
			(start 0.12065 0.3048)
			(end 0.67945 0.3048)
			(stroke
				(width 0.1)
				(type default)
			)
			(layer "B.Fab")
		)
		(fp_line
			(start -0.120396 0.3048)
			(end -0.120396 0.2794)
			(stroke
				(width 0.1)
				(type default)
			)
			(layer "B.Fab")
		)
		(fp_line
			(start -0.67945 0.3048)
			(end -0.120396 0.3048)
			(stroke
				(width 0.1)
				(type default)
			)
			(layer "B.Fab")
		)
		(pad "1" smd circle
			(at 0.40005 0 270)
			(size 0 0)
			(layers "B.Cu" "B.Mask" "B.Paste")
			(net "NC_P0V9_RETIMER_CPU0_IMON6")
		)
		(pad "2" smd circle
			(at -0.40005 0 270)
			(size 0 0)
			(layers "B.Cu" "B.Mask" "B.Paste")
			(net "GND")
		)
	)
)
